# T6G (Grand Teton) — schematic netlist excerpt (pin names and nets, part order shuffled) for the footprints in the layout excerpt that follows; sources: Cadence DE-HDL packaged netlist, KiCad conversion of 04192023_DAF0TMB3IC0_F0TG_MB_C_brd_V02_OCP.brd

R8224  Q_RES  0 5% CHIP  pkg 0402LF  page 217 : A = PVDDIO_P1_EN ; B = PVDDIO_P1_EN_R

U19  M24M02DRMN6TP  M24M02-DRMN6TP IC  pkg SOIC8XH  page 333
  DU1  = NC
  DU2  = NC
  E2  = U19_E2
  VSS  = GND
  SDA  = SMB_RT_CPU1_P1_ROM_SDA
  SCL  = SMB_RT_CPU1_P1_ROM_SCL
  WC_N  = GND
  VCC  = P1V8_CPU1_RT_1D

(kicad_pcb
	(version 20260206)
	(generator "pcbnew")
	(generator_version "10.0")
	(general
		(thickness 1.6)
		(legacy_teardrops no)
	)
	(paper "A4")
	(title_block
		(title "04192023_DAF0TMB3IC0_F0TG_MB_C_brd_V02_OCP.brd")
		(comment 1 "Grand Teton / footprints 3447-3448 of 8354")
	)
	(layers
		(0 "F.Cu" signal "TOP")
		(4 "In1.Cu" signal "GND")
		(6 "In2.Cu" signal "IN1")
		(8 "In3.Cu" signal "GND1")
		(10 "In4.Cu" signal "IN2")
		(12 "In5.Cu" signal "GND2")
		(14 "In6.Cu" signal "IN3")
		(16 "In7.Cu" signal "GND3")
		(18 "In8.Cu" signal "VCC")
		(20 "In9.Cu" signal "VCC1")
		(22 "In10.Cu" signal "GND4")
		(24 "In11.Cu" signal "IN4")
		(26 "In12.Cu" signal "GND5")
		(28 "In13.Cu" signal "IN5")
		(30 "In14.Cu" signal "GND6")
		(32 "In15.Cu" signal "IN6")
		(34 "In16.Cu" signal "GND7")
		(2 "B.Cu" signal "BOTTOM")
		(9 "F.Adhes" user "F.Adhesive")
		(11 "B.Adhes" user "B.Adhesive")
		(13 "F.Paste" user "Package Geometry/Pastemask Top")
		(15 "B.Paste" user "Package Geometry/Pastemask Bottom")
		(5 "F.SilkS" user "Ref Des/Silkscreen Top")
		(7 "B.SilkS" user "Ref Des/Silkscreen Bottom")
		(1 "F.Mask" user "Board Geometry/Soldermask Top")
		(3 "B.Mask" user "Board Geometry/Soldermask Bottom")
		(17 "Dwgs.User" user "User.Drawings")
		(19 "Cmts.User" user "User.Comments")
		(21 "Eco1.User" user "User.Eco1")
		(23 "Eco2.User" user "User.Eco2")
		(25 "Edge.Cuts" user "Board Geometry/Outline")
		(27 "Margin" user)
		(31 "F.CrtYd" user "Package Geometry/Place Bound Top")
		(29 "B.CrtYd" user "Package Geometry/Place Bound Bottom")
		(35 "F.Fab" user "Ref Des/Assembly Top")
		(33 "B.Fab" user "Ref Des/Assembly Bottom")
	)
	(footprint ""
		(layer "F.Cu")
		(at 109.949996 -401.329906 -90)
		(property "Reference" "U19"
			(at 4.252468 -3.081782 90)
			(unlocked yes)
			(layer "F.SilkS")
			(effects
				(font
					(size 0.7874 0.5842)
					(thickness 0.1524)
				)
				(justify left)
			)
		)
		(property "Value" ""
			(at 0 0 270)
			(layer "F.Fab")
			(effects
				(font
					(size 1.27 1.27)
				)
			)
		)
		(duplicate_pad_numbers_are_jumpers no)
		(fp_line
			(start -1.8288 2.500122)
			(end 1.8288 2.500122)
			(stroke
				(width 0.1524)
				(type default)
			)
			(layer "F.SilkS")
		)
		(fp_line
			(start 1.8288 2.500122)
			(end 1.8288 -2.500122)
			(stroke
				(width 0.1524)
				(type default)
			)
			(layer "F.SilkS")
		)
		(fp_line
			(start 0 -1.4224)
			(end -1.077722 -2.500122)
			(stroke
				(width 0.1524)
				(type default)
			)
			(layer "F.SilkS")
		)
		(fp_line
			(start -1.8288 -2.500122)
			(end -1.8288 2.500122)
			(stroke
				(width 0.1524)
				(type default)
			)
			(layer "F.SilkS")
		)
		(fp_line
			(start -1.077722 -2.500122)
			(end -1.8288 -2.500122)
			(stroke
				(width 0.1524)
				(type default)
			)
			(layer "F.SilkS")
		)
		(fp_line
			(start 1.077722 -2.500122)
			(end 0 -1.4224)
			(stroke
				(width 0.1524)
				(type default)
			)
			(layer "F.SilkS")
		)
		(fp_line
			(start 1.8288 -2.500122)
			(end 1.077722 -2.500122)
			(stroke
				(width 0.1524)
				(type default)
			)
			(layer "F.SilkS")
		)
		(fp_poly
			(pts
				(xy -4.5085 -2.413) (xy -4.5085 -1.397) (xy -3.4925 -1.905)
			)
			(stroke
				(width 0)
				(type default)
			)
			(fill yes)
			(layer "F.SilkS")
		)
		(fp_line
			(start -1.999996 2.500122)
			(end 1.999996 2.500122)
			(stroke
				(width 0.1)
				(type default)
			)
			(layer "F.Fab")
		)
		(fp_line
			(start 1.999996 2.500122)
			(end 1.999996 -2.500122)
			(stroke
				(width 0.1)
				(type default)
			)
			(layer "F.Fab")
		)
		(fp_line
			(start -1.999996 -2.500122)
			(end -1.999996 2.500122)
			(stroke
				(width 0.1)
				(type default)
			)
			(layer "F.Fab")
		)
		(fp_line
			(start 1.999996 -2.500122)
			(end -1.999996 -2.500122)
			(stroke
				(width 0.1)
				(type default)
			)
			(layer "F.Fab")
		)
		(fp_poly
			(pts
				(xy -4.5085 -2.413) (xy -4.5085 -1.397) (xy -3.4925 -1.905)
			)
			(stroke
				(width 0)
				(type default)
			)
			(fill yes)
			(layer "F.Fab")
		)
		(pad "1" smd rect
			(at -2.599944 -1.905 180)
			(size 0.889 1.27)
			(layers "F.Cu" "F.Mask" "F.Paste")
			(net "Net_10837")
		)
		(pad "2" smd rect
			(at -2.599944 -0.635 180)
			(size 0.889 1.27)
			(layers "F.Cu" "F.Mask" "F.Paste")
			(net "Net_10836")
		)
		(pad "3" smd rect
			(at -2.599944 0.635 180)
			(size 0.889 1.27)
			(layers "F.Cu" "F.Mask" "F.Paste")
			(net "U19_E2")
		)
		(pad "4" smd rect
			(at -2.599944 1.905 180)
			(size 0.889 1.27)
			(layers "F.Cu" "F.Mask" "F.Paste")
			(net "GND")
		)
		(pad "5" smd rect
			(at 2.599944 1.905 180)
			(size 0.889 1.27)
			(layers "F.Cu" "F.Mask" "F.Paste")
			(net "SMB_RT_CPU1_P1_ROM_SDA")
		)
		(pad "6" smd rect
			(at 2.599944 0.635 180)
			(size 0.889 1.27)
			(layers "F.Cu" "F.Mask" "F.Paste")
			(net "SMB_RT_CPU1_P1_ROM_SCL")
		)
		(pad "7" smd rect
			(at 2.599944 -0.635 180)
			(size 0.889 1.27)
			(layers "F.Cu" "F.Mask" "F.Paste")
			(net "GND")
		)
		(pad "8" smd rect
			(at 2.599944 -1.905 180)
			(size 0.889 1.27)
			(layers "F.Cu" "F.Mask" "F.Paste")
			(net "P1V8_CPU1_RT_1D")
		)
	)
	(footprint ""
		(layer "F.Cu")
		(at 20.416012 -358.30637 90)
		(property "Reference" "R8224"
			(at 0 0 90)
			(layer "F.SilkS")
			(hide yes)
			(effects
				(font
					(size 1.27 1.27)
				)
			)
		)
		(property "Value" ""
			(at 0 0 90)
			(layer "F.Fab")
			(effects
				(font
					(size 1.27 1.27)
				)
			)
		)
		(duplicate_pad_numbers_are_jumpers no)
		(fp_line
			(start 0.7874 -0.4064)
			(end 0.7874 0.4064)
			(stroke
				(width 0.1524)
				(type default)
			)
			(layer "F.SilkS")
		)
		(fp_line
			(start -0.7874 -0.4064)
			(end 0.7874 -0.4064)
			(stroke
				(width 0.1524)
				(type default)
			)
			(layer "F.SilkS")
		)
		(fp_line
			(start 0.7874 0.4064)
			(end -0.7874 0.4064)
			(stroke
				(width 0.1524)
				(type default)
			)
			(layer "F.SilkS")
		)
		(fp_line
			(start -0.7874 0.4064)
			(end -0.7874 -0.4064)
			(stroke
				(width 0.1524)
				(type default)
			)
			(layer "F.SilkS")
		)
		(fp_line
			(start -0.12065 -0.305054)
			(end -0.12065 -0.2794)
			(stroke
				(width 0.1)
				(type default)
			)
			(layer "F.Fab")
		)
		(fp_line
			(start -0.67945 -0.305054)
			(end -0.12065 -0.305054)
			(stroke
				(width 0.1)
				(type default)
			)
			(layer "F.Fab")
		)
		(fp_line
			(start 0.67945 -0.3048)
			(end 0.67945 0.3048)
			(stroke
				(width 0.1)
				(type default)
			)
			(layer "F.Fab")
		)
		(fp_line
			(start 0.12065 -0.3048)
			(end 0.67945 -0.3048)
			(stroke
				(width 0.1)
				(type default)
			)
			(layer "F.Fab")
		)
		(fp_line
			(start 0.12065 -0.2794)
			(end 0.12065 -0.3048)
			(stroke
				(width 0.1)
				(type default)
			)
			(layer "F.Fab")
		)
		(fp_line
			(start -0.12065 -0.2794)
			(end 0.12065 -0.2794)
			(stroke
				(width 0.1)
				(type default)
			)
			(layer "F.Fab")
		)
		(fp_line
			(start 0.120396 0.2794)
			(end -0.12065 0.2794)
			(stroke
				(width 0.1)
				(type default)
			)
			(layer "F.Fab")
		)
		(fp_line
			(start -0.12065 0.2794)
			(end -0.12065 0.3048)
			(stroke
				(width 0.1)
				(type default)
			)
			(layer "F.Fab")
		)
		(fp_line
			(start 0.67945 0.3048)
			(end 0.120396 0.3048)
			(stroke
				(width 0.1)
				(type default)
			)
			(layer "F.Fab")
		)
		(fp_line
			(start 0.120396 0.3048)
			(end 0.120396 0.2794)
			(stroke
				(width 0.1)
				(type default)
			)
			(layer "F.Fab")
		)
		(fp_line
			(start -0.12065 0.3048)
			(end -0.67945 0.3048)
			(stroke
				(width 0.1)
				(type default)
			)
			(layer "F.Fab")
		)
		(fp_line
			(start -0.67945 0.3048)
			(end -0.67945 -0.305054)
			(stroke
				(width 0.1)
				(type default)
			)
			(layer "F.Fab")
		)
		(pad "1" smd circle
			(at -0.40005 0 90)
			(size 0 0)
			(layers "F.Cu" "F.Mask" "F.Paste")
			(net "PVDDIO_P1_EN")
		)
		(pad "2" smd circle
			(at 0.40005 0 90)
			(size 0 0)
			(layers "F.Cu" "F.Mask" "F.Paste")
			(net "PVDDIO_P1_EN_R")
		)
	)
)
